# T6G (Grand Teton) — schematic netlist excerpt (pin names and nets, part order shuffled) for the footprints in the layout excerpt that follows; sources: Cadence DE-HDL packaged netlist, KiCad conversion of 04192023_DAF0TMB3IC0_F0TG_MB_C_brd_V02_OCP.brd

R6251  Q_RES  4.7K 1% EMPTY  pkg 0402LF  page 271 : A = GND ; B = HSC_TYPE_ADC_A0

U146  SN74AVC2T245RSWR  IC  pkg UQFN10_0-4_1-8X1-4  page 172
  DIR2  = GND
  \oe_#\  = JTAG_BMC_R_D_OE
  GND  = GND
  B2  = JTAG_TDO_R1
  B1  = JTAG_TDI_R
  VCCB  = PVDD18_S5_P0
  VCCA  = PVDD18_S5_P0
  A1  = HDT_HDR_TDI
  A2  = HDT_HDR_TDO_R
  DIR1  = PVDD18_S5_P0

(kicad_pcb
	(version 20260206)
	(generator "pcbnew")
	(generator_version "10.0")
	(general
		(thickness 1.6)
		(legacy_teardrops no)
	)
	(paper "A4")
	(title_block
		(title "04192023_DAF0TMB3IC0_F0TG_MB_C_brd_V02_OCP.brd")
		(comment 1 "Grand Teton / footprints 1767-1768 of 8354")
	)
	(layers
		(0 "F.Cu" signal "TOP")
		(4 "In1.Cu" signal "GND")
		(6 "In2.Cu" signal "IN1")
		(8 "In3.Cu" signal "GND1")
		(10 "In4.Cu" signal "IN2")
		(12 "In5.Cu" signal "GND2")
		(14 "In6.Cu" signal "IN3")
		(16 "In7.Cu" signal "GND3")
		(18 "In8.Cu" signal "VCC")
		(20 "In9.Cu" signal "VCC1")
		(22 "In10.Cu" signal "GND4")
		(24 "In11.Cu" signal "IN4")
		(26 "In12.Cu" signal "GND5")
		(28 "In13.Cu" signal "IN5")
		(30 "In14.Cu" signal "GND6")
		(32 "In15.Cu" signal "IN6")
		(34 "In16.Cu" signal "GND7")
		(2 "B.Cu" signal "BOTTOM")
		(9 "F.Adhes" user "F.Adhesive")
		(11 "B.Adhes" user "B.Adhesive")
		(13 "F.Paste" user "Package Geometry/Pastemask Top")
		(15 "B.Paste" user "Package Geometry/Pastemask Bottom")
		(5 "F.SilkS" user "Ref Des/Silkscreen Top")
		(7 "B.SilkS" user "Ref Des/Silkscreen Bottom")
		(1 "F.Mask" user "Board Geometry/Soldermask Top")
		(3 "B.Mask" user "Board Geometry/Soldermask Bottom")
		(17 "Dwgs.User" user "User.Drawings")
		(19 "Cmts.User" user "User.Comments")
		(21 "Eco1.User" user "User.Eco1")
		(23 "Eco2.User" user "User.Eco2")
		(25 "Edge.Cuts" user "Board Geometry/Outline")
		(27 "Margin" user)
		(31 "F.CrtYd" user "Package Geometry/Place Bound Top")
		(29 "B.CrtYd" user "Package Geometry/Place Bound Bottom")
		(35 "F.Fab" user "Ref Des/Assembly Top")
		(33 "B.Fab" user "Ref Des/Assembly Bottom")
	)
	(footprint ""
		(layer "F.Cu")
		(at 123.127516 -54.775608 90)
		(property "Reference" "U146"
			(at 0.67818 -2.174748 90)
			(unlocked yes)
			(layer "F.SilkS")
			(effects
				(font
					(size 0.7874 0.5842)
					(thickness 0.1524)
				)
				(justify left)
			)
		)
		(property "Value" ""
			(at 0 0 90)
			(layer "F.Fab")
			(effects
				(font
					(size 1.27 1.27)
				)
			)
		)
		(duplicate_pad_numbers_are_jumpers no)
		(fp_line
			(start 1.245616 -1.445768)
			(end 1.245616 1.445768)
			(stroke
				(width 0.1524)
				(type default)
			)
			(layer "F.SilkS")
		)
		(fp_line
			(start -1.245616 -1.445768)
			(end 1.245616 -1.445768)
			(stroke
				(width 0.1524)
				(type default)
			)
			(layer "F.SilkS")
		)
		(fp_line
			(start 1.245616 1.445768)
			(end -1.245616 1.445768)
			(stroke
				(width 0.1524)
				(type default)
			)
			(layer "F.SilkS")
		)
		(fp_line
			(start -1.245616 1.445768)
			(end -1.245616 -1.445768)
			(stroke
				(width 0.1524)
				(type default)
			)
			(layer "F.SilkS")
		)
		(fp_poly
			(pts
				(xy -1.371346 -0.199136) (xy -1.879346 0.054864) (xy -1.879346 -0.453136)
			)
			(stroke
				(width 0)
				(type default)
			)
			(fill yes)
			(layer "F.SilkS")
		)
		(fp_line
			(start 0.724916 -0.925068)
			(end 0.724916 0.925068)
			(stroke
				(width 0.1)
				(type default)
			)
			(layer "F.Fab")
		)
		(fp_line
			(start -0.724916 -0.925068)
			(end 0.724916 -0.925068)
			(stroke
				(width 0.1)
				(type default)
			)
			(layer "F.Fab")
		)
		(fp_line
			(start 0.724916 0.925068)
			(end -0.724916 0.925068)
			(stroke
				(width 0.1)
				(type default)
			)
			(layer "F.Fab")
		)
		(fp_line
			(start -0.724916 0.925068)
			(end -0.724916 -0.925068)
			(stroke
				(width 0.1)
				(type default)
			)
			(layer "F.Fab")
		)
		(fp_poly
			(pts
				(xy -1.894586 -0.453898) (xy -1.894586 0.054102) (xy -1.386586 -0.199898)
			)
			(stroke
				(width 0)
				(type default)
			)
			(fill yes)
			(layer "F.Fab")
		)
		(pad "1" smd circle
			(at -0.649986 -0.199898)
			(size 0 0)
			(layers "F.Cu" "F.Mask" "F.Paste")
			(net "GND")
		)
		(pad "2" smd rect
			(at -0.700024 0.199898 180)
			(size 0.1778 0.8128)
			(layers "F.Cu" "F.Mask" "F.Paste")
			(net "JTAG_BMC_R_D_OE")
		)
		(pad "3" smd rect
			(at -0.40005 0.899922 90)
			(size 0.1778 0.8128)
			(layers "F.Cu" "F.Mask" "F.Paste")
			(net "GND")
		)
		(pad "4" smd rect
			(at 0 0.899922 90)
			(size 0.1778 0.8128)
			(layers "F.Cu" "F.Mask" "F.Paste")
			(net "JTAG_TDO_R1")
		)
		(pad "5" smd rect
			(at 0.40005 0.899922 90)
			(size 0.1778 0.8128)
			(layers "F.Cu" "F.Mask" "F.Paste")
			(net "JTAG_TDI_R")
		)
		(pad "6" smd rect
			(at 0.700024 0.199898)
			(size 0.1778 0.8128)
			(layers "F.Cu" "F.Mask" "F.Paste")
			(net "PVDD18_S5_P0")
		)
		(pad "7" smd rect
			(at 0.700024 -0.199898)
			(size 0.1778 0.8128)
			(layers "F.Cu" "F.Mask" "F.Paste")
			(net "PVDD18_S5_P0")
		)
		(pad "8" smd rect
			(at 0.40005 -0.899922 90)
			(size 0.1778 0.8128)
			(layers "F.Cu" "F.Mask" "F.Paste")
			(net "HDT_HDR_TDI")
		)
		(pad "9" smd rect
			(at 0 -0.899922 90)
			(size 0.1778 0.8128)
			(layers "F.Cu" "F.Mask" "F.Paste")
			(net "HDT_HDR_TDO_R")
		)
		(pad "10" smd rect
			(at -0.40005 -0.912622 90)
			(size 0.1778 0.7874)
			(layers "F.Cu" "F.Mask" "F.Paste")
			(net "PVDD18_S5_P0")
		)
	)
	(footprint ""
		(layer "F.Cu")
		(at 428.813722 -423.621708 90)
		(property "Reference" "R6251"
			(at 0 0 90)
			(layer "F.SilkS")
			(hide yes)
			(effects
				(font
					(size 1.27 1.27)
				)
			)
		)
		(property "Value" ""
			(at 0 0 90)
			(layer "F.Fab")
			(effects
				(font
					(size 1.27 1.27)
				)
			)
		)
		(duplicate_pad_numbers_are_jumpers no)
		(fp_line
			(start 0.7874 -0.4064)
			(end 0.7874 0.4064)
			(stroke
				(width 0.1524)
				(type default)
			)
			(layer "F.SilkS")
		)
		(fp_line
			(start -0.7874 -0.4064)
			(end 0.7874 -0.4064)
			(stroke
				(width 0.1524)
				(type default)
			)
			(layer "F.SilkS")
		)
		(fp_line
			(start 0.7874 0.4064)
			(end -0.7874 0.4064)
			(stroke
				(width 0.1524)
				(type default)
			)
			(layer "F.SilkS")
		)
		(fp_line
			(start -0.7874 0.4064)
			(end -0.7874 -0.4064)
			(stroke
				(width 0.1524)
				(type default)
			)
			(layer "F.SilkS")
		)
		(fp_line
			(start -0.12065 -0.305054)
			(end -0.12065 -0.2794)
			(stroke
				(width 0.1)
				(type default)
			)
			(layer "F.Fab")
		)
		(fp_line
			(start -0.67945 -0.305054)
			(end -0.12065 -0.305054)
			(stroke
				(width 0.1)
				(type default)
			)
			(layer "F.Fab")
		)
		(fp_line
			(start 0.67945 -0.3048)
			(end 0.67945 0.3048)
			(stroke
				(width 0.1)
				(type default)
			)
			(layer "F.Fab")
		)
		(fp_line
			(start 0.12065 -0.3048)
			(end 0.67945 -0.3048)
			(stroke
				(width 0.1)
				(type default)
			)
			(layer "F.Fab")
		)
		(fp_line
			(start 0.12065 -0.2794)
			(end 0.12065 -0.3048)
			(stroke
				(width 0.1)
				(type default)
			)
			(layer "F.Fab")
		)
		(fp_line
			(start -0.12065 -0.2794)
			(end 0.12065 -0.2794)
			(stroke
				(width 0.1)
				(type default)
			)
			(layer "F.Fab")
		)
		(fp_line
			(start 0.120396 0.2794)
			(end -0.12065 0.2794)
			(stroke
				(width 0.1)
				(type default)
			)
			(layer "F.Fab")
		)
		(fp_line
			(start -0.12065 0.2794)
			(end -0.12065 0.3048)
			(stroke
				(width 0.1)
				(type default)
			)
			(layer "F.Fab")
		)
		(fp_line
			(start 0.67945 0.3048)
			(end 0.120396 0.3048)
			(stroke
				(width 0.1)
				(type default)
			)
			(layer "F.Fab")
		)
		(fp_line
			(start 0.120396 0.3048)
			(end 0.120396 0.2794)
			(stroke
				(width 0.1)
				(type default)
			)
			(layer "F.Fab")
		)
		(fp_line
			(start -0.12065 0.3048)
			(end -0.67945 0.3048)
			(stroke
				(width 0.1)
				(type default)
			)
			(layer "F.Fab")
		)
		(fp_line
			(start -0.67945 0.3048)
			(end -0.67945 -0.305054)
			(stroke
				(width 0.1)
				(type default)
			)
			(layer "F.Fab")
		)
		(pad "1" smd circle
			(at -0.40005 0 90)
			(size 0 0)
			(layers "F.Cu" "F.Mask" "F.Paste")
			(net "GND")
		)
		(pad "2" smd circle
			(at 0.40005 0 90)
			(size 0 0)
			(layers "F.Cu" "F.Mask" "F.Paste")
			(net "HSC_TYPE_ADC_A0")
		)
	)
)
